(kicad_pcb
	(version 20260206)
	(generator "pcbnew")
	(generator_version "10.0")
	(general
		(thickness 1.6)
		(legacy_teardrops no)
	)
	(paper "A4")
	(title_block
		(title "Bryce Canyon_F.DPB_16315-1-OCP.brd")
		(comment 1 "Bryce Canyon / footprints 1647-1653 of 2223")
	)
	(layers
		(0 "F.Cu" signal "TOP")
		(4 "In1.Cu" signal "L2GND")
		(6 "In2.Cu" signal "L3")
		(8 "In3.Cu" signal "L4GND")
		(10 "In4.Cu" signal "L5")
		(12 "In5.Cu" signal "L6VCC")
		(14 "In6.Cu" signal "L7VCC")
		(16 "In7.Cu" signal "L8")
		(18 "In8.Cu" signal "L9GND")
		(20 "In9.Cu" signal "L10")
		(22 "In10.Cu" signal "L11GND")
		(2 "B.Cu" signal "BOTTOM")
		(9 "F.Adhes" user "F.Adhesive")
		(11 "B.Adhes" user "B.Adhesive")
		(13 "F.Paste" user "Package Geometry/Pastemask Top")
		(15 "B.Paste" user "Package Geometry/Pastemask Bottom")
		(5 "F.SilkS" user "Ref Des/Silkscreen Top")
		(7 "B.SilkS" user "Ref Des/Silkscreen Bottom")
		(1 "F.Mask" user "Board Geometry/Soldermask Top")
		(3 "B.Mask" user "Board Geometry/Soldermask Bottom")
		(17 "Dwgs.User" user "User.Drawings")
		(19 "Cmts.User" user "User.Comments")
		(21 "Eco1.User" user "User.Eco1")
		(23 "Eco2.User" user "User.Eco2")
		(25 "Edge.Cuts" user "Board Geometry/Outline")
		(27 "Margin" user)
		(31 "F.CrtYd" user "Package Geometry/Place Bound Top")
		(29 "B.CrtYd" user "Package Geometry/Place Bound Bottom")
		(35 "F.Fab" user "Ref Des/Assembly Top")
		(33 "B.Fab" user "Ref Des/Assembly Bottom")
	)
	(footprint ""
		(layer "F.Cu")
		(at 16.824198 -52.136294 90)
		(property "Reference" "R689"
			(at 0 0 90)
			(layer "F.SilkS")
			(hide yes)
			(effects
				(font
					(size 1.27 1.27)
				)
			)
		)
		(property "Value" "4K7R2J-2-GP"
			(at 0.064008 -3.993896 90)
			(unlocked yes)
			(layer "F.Fab")
			(hide yes)
			(effects
				(font
					(size 1.016 1.016)
					(thickness 0.1524)
				)
			)
		)
		(property "Device Type" "R402H16"
			(at 0.064008 -5.517896 90)
			(unlocked yes)
			(layer "F.Fab")
			(hide yes)
			(effects
				(font
					(size 1.016 1.016)
					(thickness 0.1524)
				)
			)
		)
		(duplicate_pad_numbers_are_jumpers no)
		(fp_line
			(start 0.508 -0.9398)
			(end -0.508 -0.9398)
			(stroke
				(width 0.1524)
				(type default)
			)
			(layer "F.SilkS")
		)
		(fp_line
			(start -0.508 -0.9398)
			(end -0.508 0.9398)
			(stroke
				(width 0.1524)
				(type default)
			)
			(layer "F.SilkS")
		)
		(fp_rect
			(start -0.508 0.9398)
			(end 0.508 -0.9398)
			(stroke
				(width 0)
				(type default)
			)
			(fill no)
			(layer "F.CrtYd")
		)
		(fp_rect
			(start -0.508 0.9398)
			(end 0.508 -0.9398)
			(stroke
				(width 0)
				(type default)
			)
			(fill no)
			(layer "F.Fab")
		)
		(pad "1" smd custom
			(at 0 -0.4445 90)
			(size 0.1397 0.1397)
			(layers "F.Cu" "F.Mask" "F.Paste")
			(net "P12V_A")
			(options
				(clearance outline)
				(anchor circle)
			)
			(primitives
				(gr_poly
					(pts
						(arc
							(start -0.1778 -0.2794)
							(mid -0.249642 -0.249642)
							(end -0.2794 -0.1778)
						)
						(arc
							(start -0.2794 0.1778)
							(mid -0.249642 0.249642)
							(end -0.1778 0.2794)
						)
						(arc
							(start 0.1778 0.2794)
							(mid 0.249642 0.249642)
							(end 0.2794 0.1778)
						)
						(arc
							(start 0.2794 -0.1778)
							(mid 0.249642 -0.249642)
							(end 0.1778 -0.2794)
						)
					)
					(width 0)
					(fill yes)
				)
			)
		)
		(pad "2" smd custom
			(at 0 0.4445 90)
			(size 0.1397 0.1397)
			(layers "F.Cu" "F.Mask" "F.Paste")
			(net "SW_HDD_P24")
			(options
				(clearance outline)
				(anchor circle)
			)
			(primitives
				(gr_poly
					(pts
						(arc
							(start -0.1778 -0.2794)
							(mid -0.249642 -0.249642)
							(end -0.2794 -0.1778)
						)
						(arc
							(start -0.2794 0.1778)
							(mid -0.249642 0.249642)
							(end -0.1778 0.2794)
						)
						(arc
							(start 0.1778 0.2794)
							(mid 0.249642 0.249642)
							(end 0.2794 0.1778)
						)
						(arc
							(start 0.2794 -0.1778)
							(mid 0.249642 -0.249642)
							(end 0.1778 -0.2794)
						)
					)
					(width 0)
					(fill yes)
				)
			)
		)
	)
	(footprint ""
		(layer "F.Cu")
		(at 32.463486 -274.219416 90)
		(property "Reference" "C506"
			(at 0 0 90)
			(layer "F.SilkS")
			(hide yes)
			(effects
				(font
					(size 1.27 1.27)
				)
			)
		)
		(property "Value" "SCD01U16V1KX-GP"
			(at -2.8321 -1.7399 90)
			(unlocked yes)
			(layer "F.Fab")
			(hide yes)
			(effects
				(font
					(size 1.016 1.016)
					(thickness 0.1524)
				)
			)
		)
		(property "Device Type" "C0201H13"
			(at -2.8321 -3.2639 90)
			(unlocked yes)
			(layer "F.Fab")
			(hide yes)
			(effects
				(font
					(size 1.016 1.016)
					(thickness 0.1524)
				)
			)
		)
		(duplicate_pad_numbers_are_jumpers no)
		(fp_rect
			(start -0.2794 0.6477)
			(end 0.2794 -0.6477)
			(stroke
				(width 0)
				(type default)
			)
			(fill no)
			(layer "F.CrtYd")
		)
		(fp_rect
			(start -0.2794 0.6477)
			(end 0.2794 -0.6477)
			(stroke
				(width 0)
				(type default)
			)
			(fill no)
			(layer "F.Fab")
		)
		(pad "1" smd custom
			(at 0 -0.2794 90)
			(size 0.0762 0.0762)
			(layers "F.Cu" "F.Mask" "F.Paste")
			(net "SAS_HDD_RX_N0")
			(options
				(clearance outline)
				(anchor circle)
			)
			(primitives
				(gr_poly
					(pts
						(arc
							(start 0.1524 -0.127)
							(mid 0.137521 -0.162921)
							(end 0.1016 -0.1778)
						)
						(arc
							(start -0.1016 -0.1778)
							(mid -0.137521 -0.162921)
							(end -0.1524 -0.127)
						)
						(arc
							(start -0.1524 0.127)
							(mid -0.137521 0.162921)
							(end -0.1016 0.1778)
						)
						(arc
							(start 0.1016 0.1778)
							(mid 0.137521 0.162921)
							(end 0.1524 0.127)
						)
					)
					(width 0)
					(fill yes)
				)
			)
		)
		(pad "2" smd custom
			(at 0 0.2794 90)
			(size 0.0762 0.0762)
			(layers "F.Cu" "F.Mask" "F.Paste")
			(net "PHY_SCC_A_TO_DRV_A_0_DN")
			(options
				(clearance outline)
				(anchor circle)
			)
			(primitives
				(gr_poly
					(pts
						(arc
							(start 0.1524 -0.127)
							(mid 0.137521 -0.162921)
							(end 0.1016 -0.1778)
						)
						(arc
							(start -0.1016 -0.1778)
							(mid -0.137521 -0.162921)
							(end -0.1524 -0.127)
						)
						(arc
							(start -0.1524 0.127)
							(mid -0.137521 0.162921)
							(end -0.1016 0.1778)
						)
						(arc
							(start 0.1016 0.1778)
							(mid 0.137521 0.162921)
							(end 0.1524 0.127)
						)
					)
					(width 0)
					(fill yes)
				)
			)
		)
	)
	(footprint ""
		(layer "F.Cu")
		(at 80.24495 -242.25377)
		(property "Reference" "R217"
			(at 0 0 0)
			(layer "F.SilkS")
			(hide yes)
			(effects
				(font
					(size 1.27 1.27)
				)
			)
		)
		(property "Value" "130R3F-GP"
			(at -0.0254 -2.5146 0)
			(unlocked yes)
			(layer "F.Fab")
			(hide yes)
			(effects
				(font
					(size 1.016 1.016)
					(thickness 0.1524)
				)
			)
		)
		(property "Device Type" "R603H22"
			(at -0.0254 -4.0386 0)
			(unlocked yes)
			(layer "F.Fab")
			(hide yes)
			(effects
				(font
					(size 1.016 1.016)
					(thickness 0.1524)
				)
			)
		)
		(duplicate_pad_numbers_are_jumpers no)
		(fp_line
			(start -0.4826 0)
			(end -0.2032 0)
			(stroke
				(width 0.2032)
				(type default)
			)
			(layer "F.SilkS")
		)
		(fp_line
			(start 0.2032 0)
			(end 0.4826 0)
			(stroke
				(width 0.2032)
				(type default)
			)
			(layer "F.SilkS")
		)
		(fp_rect
			(start -0.5842 1.3335)
			(end 0.5842 -1.3335)
			(stroke
				(width 0)
				(type default)
			)
			(fill no)
			(layer "F.CrtYd")
		)
		(fp_rect
			(start -0.5842 1.3335)
			(end 0.5842 -1.3335)
			(stroke
				(width 0)
				(type default)
			)
			(fill no)
			(layer "F.Fab")
		)
		(pad "1" smd custom
			(at 0 -0.762)
			(size 0.2159 0.2159)
			(layers "F.Cu" "F.Mask" "F.Paste")
			(net "P5V_A_1")
			(options
				(clearance outline)
				(anchor circle)
			)
			(primitives
				(gr_poly
					(pts
						(arc
							(start -0.3302 -0.4318)
							(mid -0.402042 -0.402042)
							(end -0.4318 -0.3302)
						)
						(arc
							(start -0.4318 0.3302)
							(mid -0.402042 0.402042)
							(end -0.3302 0.4318)
						)
						(arc
							(start 0.3302 0.4318)
							(mid 0.402042 0.402042)
							(end 0.4318 0.3302)
						)
						(arc
							(start 0.4318 -0.3302)
							(mid 0.402042 -0.402042)
							(end 0.3302 -0.4318)
						)
					)
					(width 0)
					(fill yes)
				)
			)
		)
		(pad "2" smd custom
			(at 0 0.762)
			(size 0.2159 0.2159)
			(layers "F.Cu" "F.Mask" "F.Paste")
			(net "FLT_HDD2")
			(options
				(clearance outline)
				(anchor circle)
			)
			(primitives
				(gr_poly
					(pts
						(arc
							(start -0.3302 -0.4318)
							(mid -0.402042 -0.402042)
							(end -0.4318 -0.3302)
						)
						(arc
							(start -0.4318 0.3302)
							(mid -0.402042 0.402042)
							(end -0.3302 0.4318)
						)
						(arc
							(start 0.3302 0.4318)
							(mid 0.402042 0.402042)
							(end 0.4318 0.3302)
						)
						(arc
							(start 0.4318 -0.3302)
							(mid 0.402042 -0.402042)
							(end 0.3302 -0.4318)
						)
					)
					(width 0)
					(fill yes)
				)
			)
		)
	)
	(footprint ""
		(layer "F.Cu")
		(at 431.581052 -45.735494 180)
		(property "Reference" "R902"
			(at 0 0 180)
			(layer "F.SilkS")
			(hide yes)
			(effects
				(font
					(size 1.27 1.27)
				)
			)
		)
		(property "Value" "4K7R2J-2-GP"
			(at 0.064008 -3.993896 180)
			(unlocked yes)
			(layer "F.Fab")
			(hide yes)
			(effects
				(font
					(size 1.016 1.016)
					(thickness 0.1524)
				)
			)
		)
		(property "Device Type" "R402H16"
			(at 0.064008 -5.517896 180)
			(unlocked yes)
			(layer "F.Fab")
			(hide yes)
			(effects
				(font
					(size 1.016 1.016)
					(thickness 0.1524)
				)
			)
		)
		(duplicate_pad_numbers_are_jumpers no)
		(fp_line
			(start 0.508 -0.9398)
			(end -0.508 -0.9398)
			(stroke
				(width 0.1524)
				(type default)
			)
			(layer "F.SilkS")
		)
		(fp_line
			(start -0.508 -0.9398)
			(end -0.508 0.9398)
			(stroke
				(width 0.1524)
				(type default)
			)
			(layer "F.SilkS")
		)
		(fp_rect
			(start -0.508 0.9398)
			(end 0.508 -0.9398)
			(stroke
				(width 0)
				(type default)
			)
			(fill no)
			(layer "F.CrtYd")
		)
		(fp_rect
			(start -0.508 0.9398)
			(end 0.508 -0.9398)
			(stroke
				(width 0)
				(type default)
			)
			(fill no)
			(layer "F.Fab")
		)
		(pad "1" smd custom
			(at 0 -0.4445 180)
			(size 0.1397 0.1397)
			(layers "F.Cu" "F.Mask" "F.Paste")
			(net "P12V_A")
			(options
				(clearance outline)
				(anchor circle)
			)
			(primitives
				(gr_poly
					(pts
						(arc
							(start -0.1778 -0.2794)
							(mid -0.249642 -0.249642)
							(end -0.2794 -0.1778)
						)
						(arc
							(start -0.2794 0.1778)
							(mid -0.249642 0.249642)
							(end -0.1778 0.2794)
						)
						(arc
							(start 0.1778 0.2794)
							(mid 0.249642 0.249642)
							(end 0.2794 0.1778)
						)
						(arc
							(start 0.2794 -0.1778)
							(mid 0.249642 -0.249642)
							(end 0.1778 -0.2794)
						)
					)
					(width 0)
					(fill yes)
				)
			)
		)
		(pad "2" smd custom
			(at 0 0.4445 180)
			(size 0.1397 0.1397)
			(layers "F.Cu" "F.Mask" "F.Paste")
			(net "SW_HDD_R33")
			(options
				(clearance outline)
				(anchor circle)
			)
			(primitives
				(gr_poly
					(pts
						(arc
							(start -0.1778 -0.2794)
							(mid -0.249642 -0.249642)
							(end -0.2794 -0.1778)
						)
						(arc
							(start -0.2794 0.1778)
							(mid -0.249642 0.249642)
							(end -0.1778 0.2794)
						)
						(arc
							(start 0.1778 0.2794)
							(mid 0.249642 0.249642)
							(end 0.2794 0.1778)
						)
						(arc
							(start 0.2794 -0.1778)
							(mid 0.249642 -0.249642)
							(end 0.1778 -0.2794)
						)
					)
					(width 0)
					(fill yes)
				)
			)
		)
	)
	(footprint ""
		(layer "F.Cu")
		(at 452.797164 -242.250976)
		(property "Reference" "R269"
			(at 0 0 0)
			(layer "F.SilkS")
			(hide yes)
			(effects
				(font
					(size 1.27 1.27)
				)
			)
		)
		(property "Value" "91R3F-1-GP"
			(at -0.0254 -2.5146 0)
			(unlocked yes)
			(layer "F.Fab")
			(hide yes)
			(effects
				(font
					(size 1.016 1.016)
					(thickness 0.1524)
				)
			)
		)
		(property "Device Type" "R603H22"
			(at -0.0254 -4.0386 0)
			(unlocked yes)
			(layer "F.Fab")
			(hide yes)
			(effects
				(font
					(size 1.016 1.016)
					(thickness 0.1524)
				)
			)
		)
		(duplicate_pad_numbers_are_jumpers no)
		(fp_line
			(start -0.4826 0)
			(end -0.2032 0)
			(stroke
				(width 0.2032)
				(type default)
			)
			(layer "F.SilkS")
		)
		(fp_line
			(start 0.2032 0)
			(end 0.4826 0)
			(stroke
				(width 0.2032)
				(type default)
			)
			(layer "F.SilkS")
		)
		(fp_rect
			(start -0.5842 1.3335)
			(end 0.5842 -1.3335)
			(stroke
				(width 0)
				(type default)
			)
			(fill no)
			(layer "F.CrtYd")
		)
		(fp_rect
			(start -0.5842 1.3335)
			(end 0.5842 -1.3335)
			(stroke
				(width 0)
				(type default)
			)
			(fill no)
			(layer "F.Fab")
		)
		(pad "1" smd custom
			(at 0 -0.762)
			(size 0.2159 0.2159)
			(layers "F.Cu" "F.Mask" "F.Paste")
			(net "P5V_A_3")
			(options
				(clearance outline)
				(anchor circle)
			)
			(primitives
				(gr_poly
					(pts
						(arc
							(start -0.3302 -0.4318)
							(mid -0.402042 -0.402042)
							(end -0.4318 -0.3302)
						)
						(arc
							(start -0.4318 0.3302)
							(mid -0.402042 0.402042)
							(end -0.3302 0.4318)
						)
						(arc
							(start 0.3302 0.4318)
							(mid 0.402042 0.402042)
							(end 0.4318 0.3302)
						)
						(arc
							(start 0.4318 -0.3302)
							(mid 0.402042 -0.402042)
							(end 0.3302 -0.4318)
						)
					)
					(width 0)
					(fill yes)
				)
			)
		)
		(pad "2" smd custom
			(at 0 0.762)
			(size 0.2159 0.2159)
			(layers "F.Cu" "F.Mask" "F.Paste")
			(net "DRV_ACT_11")
			(options
				(clearance outline)
				(anchor circle)
			)
			(primitives
				(gr_poly
					(pts
						(arc
							(start -0.3302 -0.4318)
							(mid -0.402042 -0.402042)
							(end -0.4318 -0.3302)
						)
						(arc
							(start -0.4318 0.3302)
							(mid -0.402042 0.402042)
							(end -0.3302 0.4318)
						)
						(arc
							(start 0.3302 0.4318)
							(mid 0.402042 0.402042)
							(end 0.4318 0.3302)
						)
						(arc
							(start 0.4318 -0.3302)
							(mid 0.402042 -0.402042)
							(end 0.3302 -0.4318)
						)
					)
					(width 0)
					(fill yes)
				)
			)
		)
	)
	(footprint ""
		(layer "F.Cu")
		(at 432.724052 -279.443942 90)
		(property "Reference" "R353"
			(at 0 0 90)
			(layer "F.SilkS")
			(hide yes)
			(effects
				(font
					(size 1.27 1.27)
				)
			)
		)
		(property "Value" "200KR2F-L-GP"
			(at 0.064008 -3.993896 90)
			(unlocked yes)
			(layer "F.Fab")
			(hide yes)
			(effects
				(font
					(size 1.016 1.016)
					(thickness 0.1524)
				)
			)
		)
		(property "Device Type" "R402H16"
			(at 0.064008 -5.517896 90)
			(unlocked yes)
			(layer "F.Fab")
			(hide yes)
			(effects
				(font
					(size 1.016 1.016)
					(thickness 0.1524)
				)
			)
		)
		(duplicate_pad_numbers_are_jumpers no)
		(fp_line
			(start 0.508 -0.9398)
			(end -0.508 -0.9398)
			(stroke
				(width 0.1524)
				(type default)
			)
			(layer "F.SilkS")
		)
		(fp_line
			(start -0.508 -0.9398)
			(end -0.508 0.9398)
			(stroke
				(width 0.1524)
				(type default)
			)
			(layer "F.SilkS")
		)
		(fp_rect
			(start -0.508 0.9398)
			(end 0.508 -0.9398)
			(stroke
				(width 0)
				(type default)
			)
			(fill no)
			(layer "F.CrtYd")
		)
		(fp_rect
			(start -0.508 0.9398)
			(end 0.508 -0.9398)
			(stroke
				(width 0)
				(type default)
			)
			(fill no)
			(layer "F.Fab")
		)
		(pad "1" smd custom
			(at 0 -0.4445 90)
			(size 0.1397 0.1397)
			(layers "F.Cu" "F.Mask" "F.Paste")
			(net "SW_HDD_R9")
			(options
				(clearance outline)
				(anchor circle)
			)
			(primitives
				(gr_poly
					(pts
						(arc
							(start -0.1778 -0.2794)
							(mid -0.249642 -0.249642)
							(end -0.2794 -0.1778)
						)
						(arc
							(start -0.2794 0.1778)
							(mid -0.249642 0.249642)
							(end -0.1778 0.2794)
						)
						(arc
							(start 0.1778 0.2794)
							(mid 0.249642 0.249642)
							(end 0.2794 0.1778)
						)
						(arc
							(start 0.2794 -0.1778)
							(mid 0.249642 -0.249642)
							(end 0.1778 -0.2794)
						)
					)
					(width 0)
					(fill yes)
				)
			)
		)
		(pad "2" smd custom
			(at 0 0.4445 90)
			(size 0.1397 0.1397)
			(layers "F.Cu" "F.Mask" "F.Paste")
			(net "SW_HDD_N9")
			(options
				(clearance outline)
				(anchor circle)
			)
			(primitives
				(gr_poly
					(pts
						(arc
							(start -0.1778 -0.2794)
							(mid -0.249642 -0.249642)
							(end -0.2794 -0.1778)
						)
						(arc
							(start -0.2794 0.1778)
							(mid -0.249642 0.249642)
							(end -0.1778 0.2794)
						)
						(arc
							(start 0.1778 0.2794)
							(mid 0.249642 0.249642)
							(end 0.2794 0.1778)
						)
						(arc
							(start 0.2794 -0.1778)
							(mid 0.249642 -0.249642)
							(end 0.1778 -0.2794)
						)
					)
					(width 0)
					(fill yes)
				)
			)
		)
	)
	(footprint ""
		(layer "F.Cu")
		(at 394.56995 -61.127894 -90)
		(property "Reference" "R865"
			(at 0 0 270)
			(layer "F.SilkS")
			(hide yes)
			(effects
				(font
					(size 1.27 1.27)
				)
			)
		)
		(property "Value" "2R6F-GP"
			(at -0.0508 -4.8514 270)
			(unlocked yes)
			(layer "F.Fab")
			(hide yes)
			(effects
				(font
					(size 1.016 1.016)
					(thickness 0.1524)
				)
			)
		)
		(property "Device Type" "R1206H26"
			(at 0 -6.3754 270)
			(unlocked yes)
			(layer "F.Fab")
			(hide yes)
			(effects
				(font
					(size 1.016 1.016)
					(thickness 0.1524)
				)
			)
		)
		(duplicate_pad_numbers_are_jumpers no)
		(fp_line
			(start -1.016 2.2352)
			(end -1.016 -2.2352)
			(stroke
				(width 0.1524)
				(type default)
			)
			(layer "F.SilkS")
		)
		(fp_line
			(start 1.016 2.2352)
			(end -1.016 2.2352)
			(stroke
				(width 0.1524)
				(type default)
			)
			(layer "F.SilkS")
		)
		(fp_line
			(start -1.016 -2.2352)
			(end 1.016 -2.2352)
			(stroke
				(width 0.1524)
				(type default)
			)
			(layer "F.SilkS")
		)
		(fp_line
			(start 1.016 -2.2352)
			(end 1.016 2.2352)
			(stroke
				(width 0.1524)
				(type default)
			)
			(layer "F.SilkS")
		)
		(fp_rect
			(start -1.0922 2.3114)
			(end 1.0922 -2.3114)
			(stroke
				(width 0)
				(type default)
			)
			(fill no)
			(layer "F.CrtYd")
		)
		(fp_poly
			(pts
				(xy -1.0922 -2.3114) (xy 1.0922 -2.3114) (xy 1.0922 2.3114) (xy -1.0922 2.3114)
			)
			(stroke
				(width 0)
				(type default)
			)
			(fill no)
			(layer "F.Fab")
		)
		(pad "1" smd rect
			(at 0 -1.397 270)
			(size 1.651 1.27)
			(layers "F.Cu" "F.Mask" "F.Paste")
			(net "P5V_HDD32")
		)
		(pad "2" smd rect
			(at 0 1.397 270)
			(size 1.651 1.27)
			(layers "F.Cu" "F.Mask" "F.Paste")
			(net "5V_PRE_32")
		)
	)
)
